(kicad_pcb
	(version 20240108)
	(generator "pcbnew")
	(generator_version "8.0")
	(general
		(thickness 1.586)
		(legacy_teardrops no)
	)
	(paper "A4")
	(title_block
		(title "GMSL Serializer")
		(date "2024-11-27")
		(rev "1.1.1")
		(company "Antmicro Ltd")
		(comment 1 "www.antmicro.com")
		(comment 9 "footprints 73-77 of 117")
	)
	(layers
		(0 "F.Cu" signal)
		(1 "In1.Cu" power)
		(2 "In2.Cu" power)
		(31 "B.Cu" signal)
		(32 "B.Adhes" user "B.Adhesive")
		(33 "F.Adhes" user "F.Adhesive")
		(34 "B.Paste" user)
		(35 "F.Paste" user)
		(36 "B.SilkS" user "B.Silkscreen")
		(37 "F.SilkS" user "F.Silkscreen")
		(38 "B.Mask" user)
		(39 "F.Mask" user)
		(40 "Dwgs.User" user "User.Drawings")
		(41 "Cmts.User" user "User.Comments")
		(42 "Eco1.User" user "User.Eco1")
		(43 "Eco2.User" user "User.Eco2")
		(44 "Edge.Cuts" user)
		(45 "Margin" user)
		(46 "B.CrtYd" user "B.Courtyard")
		(47 "F.CrtYd" user "F.Courtyard")
		(48 "B.Fab" user)
		(49 "F.Fab" user)
	)
	(footprint "antmicro-footprints:L_Coilcraft-PFL1609"
		(layer "F.Cu")
		(at 153.635 92.2 180)
		(property "Reference" "L6"
			(at 1.115 -0.37 0)
			(layer "F.SilkS")
			(effects
				(font
					(size 0.7 0.7)
					(thickness 0.15)
				)
				(justify right bottom)
			)
		)
		(property "Value" "L_470n_1A_Coilcraft-PFL1609"
			(at 0 2 0)
			(layer "F.Fab")
			(effects
				(font
					(size 0.7 0.7)
					(thickness 0.15)
				)
				(justify right bottom)
			)
		)
		(property "Footprint" "antmicro-footprints:L_Coilcraft-PFL1609"
			(at 0 0 180)
			(layer "F.Fab")
			(hide yes)
			(effects
				(font
					(size 1.27 1.27)
					(thickness 0.15)
				)
			)
		)
		(property "Datasheet" "https://www.coilcraft.com/getmedia/2f4cd442-d64d-4413-a518-12fcfd03318d/pfl1609.pdf"
			(at 0 0 180)
			(layer "F.Fab")
			(hide yes)
			(effects
				(font
					(size 1.27 1.27)
					(thickness 0.15)
				)
			)
		)
		(property "Author" "Antmicro"
			(at 307.27 184.4 0)
			(layer "F.Fab")
			(hide yes)
			(effects
				(font
					(size 1 1)
					(thickness 0.15)
				)
			)
		)
		(property "IMax" "1 A"
			(at 307.27 184.4 0)
			(layer "F.Fab")
			(hide yes)
			(effects
				(font
					(size 1 1)
					(thickness 0.15)
				)
			)
		)
		(property "ISat" "0.99 A"
			(at 307.27 184.4 0)
			(layer "F.Fab")
			(hide yes)
			(effects
				(font
					(size 1 1)
					(thickness 0.15)
				)
			)
		)
		(property "License" "Apache-2.0"
			(at 307.27 184.4 0)
			(layer "F.Fab")
			(hide yes)
			(effects
				(font
					(size 1 1)
					(thickness 0.15)
				)
			)
		)
		(property "MPN" "PFL1609-471"
			(at 307.27 184.4 0)
			(layer "F.Fab")
			(hide yes)
			(effects
				(font
					(size 1 1)
					(thickness 0.15)
				)
			)
		)
		(property "Manufacturer" "Coilcraft"
			(at 307.27 184.4 0)
			(layer "F.Fab")
			(hide yes)
			(effects
				(font
					(size 1 1)
					(thickness 0.15)
				)
			)
		)
		(property "Size" "1.07x1.8"
			(at 307.27 184.4 0)
			(layer "F.Fab")
			(hide yes)
			(effects
				(font
					(size 1 1)
					(thickness 0.15)
				)
			)
		)
		(property "Val" "470n/0.99A"
			(at 307.27 184.4 0)
			(layer "F.Fab")
			(hide yes)
			(effects
				(font
					(size 1 1)
					(thickness 0.15)
				)
			)
		)
		(sheetname "GMSL Connector")
		(sheetfile "GMSL.kicad_sch")
		(attr smd)
		(fp_line
			(start -0.23 0.45)
			(end 0.23 0.45)
			(stroke
				(width 0.15)
				(type solid)
			)
			(layer "F.SilkS")
		)
		(fp_line
			(start -0.23 -0.45)
			(end 0.23 -0.45)
			(stroke
				(width 0.15)
				(type solid)
			)
			(layer "F.SilkS")
		)
		(fp_rect
			(start -1.2 -0.84)
			(end 1.2 0.84)
			(stroke
				(width 0.05)
				(type solid)
			)
			(fill none)
			(layer "F.CrtYd")
		)
		(fp_rect
			(start -0.9 -0.535)
			(end 0.9 0.535)
			(stroke
				(width 0.15)
				(type solid)
			)
			(fill none)
			(layer "F.Fab")
		)
		(fp_text user "${REFERENCE}"
			(at -1.35 4 0)
			(layer "F.Fab")
			(hide yes)
			(effects
				(font
					(size 0.7 0.7)
					(thickness 0.15)
				)
				(justify right bottom)
			)
		)
		(fp_text user "Author: Antmicro"
			(at -1.35 5.2 0)
			(layer "F.Fab")
			(hide yes)
			(effects
				(font
					(size 0.7 0.7)
					(thickness 0.15)
				)
				(justify right bottom)
			)
		)
		(fp_text user "License: Apache-2.0"
			(at -1.35 6.4 0)
			(layer "F.Fab")
			(hide yes)
			(effects
				(font
					(size 0.7 0.7)
					(thickness 0.15)
				)
				(justify right bottom)
			)
		)
		(pad "1" smd roundrect
			(at -0.635 0 180)
			(size 0.64 1.02)
			(layers "F.Cu" "F.Paste" "F.Mask")
			(roundrect_rratio 0.15)
			(net 60 "Net-(L5-Pad2)")
			(pintype "passive")
		)
		(pad "2" smd roundrect
			(at 0.635 0 180)
			(size 0.64 1.02)
			(layers "F.Cu" "F.Paste" "F.Mask")
			(roundrect_rratio 0.15)
			(net 18 "/GMSL Connector/SIO_P")
			(pintype "passive")
		)
	)
	(footprint "antmicro-footprints:TP_SMD_1.5mm"
		(layer "F.Cu")
		(at 147.75 118)
		(property "Reference" "TP2"
			(at -1 -0.964 0)
			(layer "F.SilkS")
			(hide yes)
			(effects
				(font
					(size 0.7 0.7)
					(thickness 0.15)
				)
				(justify left bottom)
			)
		)
		(property "Value" "TP_1.5mm_SMD"
			(at 0 1.7 0)
			(layer "F.Fab")
			(effects
				(font
					(size 0.7 0.7)
					(thickness 0.15)
				)
				(justify left bottom)
			)
		)
		(property "Footprint" "antmicro-footprints:TP_SMD_1.5mm"
			(at 0 0 0)
			(layer "F.Fab")
			(hide yes)
			(effects
				(font
					(size 1.27 1.27)
					(thickness 0.15)
				)
			)
		)
		(property "Author" "Antmicro"
			(at 0 0 0)
			(layer "F.Fab")
			(hide yes)
			(effects
				(font
					(size 1 1)
					(thickness 0.15)
				)
			)
		)
		(property "License" "Apache-2.0"
			(at 0 0 0)
			(layer "F.Fab")
			(hide yes)
			(effects
				(font
					(size 1 1)
					(thickness 0.15)
				)
			)
		)
		(property "MPN" ""
			(at 0 0 0)
			(layer "F.Fab")
			(hide yes)
			(effects
				(font
					(size 1 1)
					(thickness 0.15)
				)
			)
		)
		(property "Manufacturer" ""
			(at 0 0 0)
			(layer "F.Fab")
			(hide yes)
			(effects
				(font
					(size 1 1)
					(thickness 0.15)
				)
			)
		)
		(sheetname "Supply")
		(sheetfile "supply.kicad_sch")
		(attr exclude_from_pos_files exclude_from_bom)
		(fp_circle
			(center 0 0)
			(end 0.85 0)
			(stroke
				(width 0.05)
				(type default)
			)
			(fill none)
			(layer "F.CrtYd")
		)
		(fp_text user "Author: Antmicro"
			(at -0.7 4.101 0)
			(layer "F.Fab")
			(hide yes)
			(effects
				(font
					(size 0.7 0.7)
					(thickness 0.15)
				)
				(justify left bottom)
			)
		)
		(fp_text user "${REFERENCE}"
			(at -0.7 2.9 0)
			(layer "F.Fab")
			(hide yes)
			(effects
				(font
					(size 0.7 0.7)
					(thickness 0.15)
				)
				(justify left bottom)
			)
		)
		(fp_text user "License: Apache-2.0"
			(at -0.7 5.301 0)
			(layer "F.Fab")
			(hide yes)
			(effects
				(font
					(size 0.7 0.7)
					(thickness 0.15)
				)
				(justify left bottom)
			)
		)
		(pad "1" smd circle
			(at 0 0 270)
			(size 1.5 1.5)
			(layers "F.Cu" "F.Mask")
			(net 11 "+1V8")
			(pinfunction "1")
			(pintype "passive")
		)
	)
	(footprint "antmicro-footprints:R_0402_1005Metric"
		(layer "F.Cu")
		(at 135.83 79.675 90)
		(descr "Resistor SMD 0402")
		(tags "resistor SMD 0402")
		(property "Reference" "R27"
			(at -0.925 -0.43 90)
			(layer "F.SilkS")
			(effects
				(font
					(size 0.7 0.7)
					(thickness 0.15)
				)
				(justify left bottom)
			)
		)
		(property "Value" "R_10k_0402"
			(at -1.011843 1.772047 90)
			(layer "F.Fab")
			(effects
				(font
					(size 0.7 0.7)
					(thickness 0.15)
				)
				(justify left bottom)
			)
		)
		(property "Footprint" "antmicro-footprints:R_0402_1005Metric"
			(at 0 0 90)
			(layer "F.Fab")
			(hide yes)
			(effects
				(font
					(size 1.27 1.27)
					(thickness 0.15)
				)
			)
		)
		(property "Datasheet" "https://www.bourns.com/docs/product-datasheets/cr.pdf"
			(at 0 0 90)
			(layer "F.Fab")
			(hide yes)
			(effects
				(font
					(size 1.27 1.27)
					(thickness 0.15)
				)
			)
		)
		(property "Author" "Antmicro"
			(at 217.125 -58.075 0)
			(layer "F.Fab")
			(hide yes)
			(effects
				(font
					(size 1 1)
					(thickness 0.15)
				)
			)
		)
		(property "License" "Apache-2.0"
			(at 217.125 -58.075 0)
			(layer "F.Fab")
			(hide yes)
			(effects
				(font
					(size 1 1)
					(thickness 0.15)
				)
			)
		)
		(property "MPN" "CR0402-FX-1002GLF"
			(at 217.125 -58.075 0)
			(layer "F.Fab")
			(hide yes)
			(effects
				(font
					(size 1 1)
					(thickness 0.15)
				)
			)
		)
		(property "Manufacturer" "Bourns"
			(at 217.125 -58.075 0)
			(layer "F.Fab")
			(hide yes)
			(effects
				(font
					(size 1 1)
					(thickness 0.15)
				)
			)
		)
		(property "Tolerance" "1%"
			(at 217.125 -58.075 0)
			(layer "F.Fab")
			(hide yes)
			(effects
				(font
					(size 1 1)
					(thickness 0.15)
				)
			)
		)
		(property "Val" "10k"
			(at 217.125 -58.075 0)
			(layer "F.Fab")
			(hide yes)
			(effects
				(font
					(size 1 1)
					(thickness 0.15)
				)
			)
		)
		(sheetname "Supply")
		(sheetfile "supply.kicad_sch")
		(attr smd)
		(fp_rect
			(start -0.925 -0.47)
			(end 0.925 0.47)
			(stroke
				(width 0.05)
				(type default)
			)
			(fill none)
			(layer "F.CrtYd")
		)
		(fp_rect
			(start -0.5 -0.25)
			(end 0.5 0.25)
			(stroke
				(width 0.15)
				(type solid)
			)
			(fill none)
			(layer "F.Fab")
		)
		(fp_text user "License: Apache-2.0"
			(at -0.95 5.169 90)
			(layer "F.Fab")
			(hide yes)
			(effects
				(font
					(size 0.7 0.7)
					(thickness 0.15)
				)
				(justify left bottom)
			)
		)
		(fp_text user "${REFERENCE}"
			(at -0.95 3.168 90)
			(layer "F.Fab")
			(hide yes)
			(effects
				(font
					(size 0.7 0.7)
					(thickness 0.15)
				)
				(justify left bottom)
			)
		)
		(fp_text user "Author: Antmicro"
			(at -0.95 4.169 90)
			(layer "F.Fab")
			(hide yes)
			(effects
				(font
					(size 0.7 0.7)
					(thickness 0.15)
				)
				(justify left bottom)
			)
		)
		(pad "1" smd roundrect
			(at -0.48 0 90)
			(size 0.59 0.64)
			(layers "F.Cu" "F.Paste" "F.Mask")
			(roundrect_rratio 0.25)
			(net 1 "GND")
			(pintype "passive")
		)
		(pad "2" smd roundrect
			(at 0.48 0 90)
			(size 0.59 0.64)
			(layers "F.Cu" "F.Paste" "F.Mask")
			(roundrect_rratio 0.25)
			(net 62 "/Supply/EN_5V")
			(pintype "passive")
		)
	)
	(footprint "antmicro-footprints:R_0402_1005Metric"
		(layer "F.Cu")
		(at 133.1 106.65 180)
		(descr "Resistor SMD 0402")
		(tags "resistor SMD 0402")
		(property "Reference" "R2"
			(at -2.566667 5.024998 0)
			(layer "F.SilkS")
			(effects
				(font
					(size 0.7 0.7)
					(thickness 0.15)
				)
				(justify right bottom)
			)
		)
		(property "Value" "R_12k_0402"
			(at -1.011843 1.772047 0)
			(layer "F.Fab")
			(effects
				(font
					(size 0.7 0.7)
					(thickness 0.15)
				)
				(justify right bottom)
			)
		)
		(property "Footprint" "antmicro-footprints:R_0402_1005Metric"
			(at 0 0 180)
			(layer "F.Fab")
			(hide yes)
			(effects
				(font
					(size 1.27 1.27)
					(thickness 0.15)
				)
			)
		)
		(property "Datasheet" "https://www.bourns.com/docs/product-datasheets/cr.pdf"
			(at 0 0 180)
			(layer "F.Fab")
			(hide yes)
			(effects
				(font
					(size 1.27 1.27)
					(thickness 0.15)
				)
			)
		)
		(property "Author" "Antmicro"
			(at 266.2 213.3 0)
			(layer "F.Fab")
			(hide yes)
			(effects
				(font
					(size 1 1)
					(thickness 0.15)
				)
			)
		)
		(property "License" "Apache-2.0"
			(at 266.2 213.3 0)
			(layer "F.Fab")
			(hide yes)
			(effects
				(font
					(size 1 1)
					(thickness 0.15)
				)
			)
		)
		(property "MPN" "CR0402-FX-1202GLF"
			(at 266.2 213.3 0)
			(layer "F.Fab")
			(hide yes)
			(effects
				(font
					(size 1 1)
					(thickness 0.15)
				)
			)
		)
		(property "Manufacturer" "Bourns"
			(at 266.2 213.3 0)
			(layer "F.Fab")
			(hide yes)
			(effects
				(font
					(size 1 1)
					(thickness 0.15)
				)
			)
		)
		(property "Tolerance" "1%"
			(at 266.2 213.3 0)
			(layer "F.Fab")
			(hide yes)
			(effects
				(font
					(size 1 1)
					(thickness 0.15)
				)
			)
		)
		(property "Val" "12k"
			(at 266.2 213.3 0)
			(layer "F.Fab")
			(hide yes)
			(effects
				(font
					(size 1 1)
					(thickness 0.15)
				)
			)
		)
		(sheetname "CSI Connector")
		(sheetfile "CSI.kicad_sch")
		(attr smd)
		(fp_rect
			(start -0.925 -0.47)
			(end 0.925 0.47)
			(stroke
				(width 0.05)
				(type default)
			)
			(fill none)
			(layer "F.CrtYd")
		)
		(fp_rect
			(start -0.5 -0.25)
			(end 0.5 0.25)
			(stroke
				(width 0.15)
				(type solid)
			)
			(fill none)
			(layer "F.Fab")
		)
		(fp_text user "Author: Antmicro"
			(at -0.95 4.169 0)
			(layer "F.Fab")
			(hide yes)
			(effects
				(font
					(size 0.7 0.7)
					(thickness 0.15)
				)
				(justify right bottom)
			)
		)
		(fp_text user "License: Apache-2.0"
			(at -0.95 5.169 0)
			(layer "F.Fab")
			(hide yes)
			(effects
				(font
					(size 0.7 0.7)
					(thickness 0.15)
				)
				(justify right bottom)
			)
		)
		(fp_text user "${REFERENCE}"
			(at -0.95 3.168 0)
			(layer "F.Fab")
			(hide yes)
			(effects
				(font
					(size 0.7 0.7)
					(thickness 0.15)
				)
				(justify right bottom)
			)
		)
		(pad "1" smd roundrect
			(at -0.48 0 180)
			(size 0.59 0.64)
			(layers "F.Cu" "F.Paste" "F.Mask")
			(roundrect_rratio 0.25)
			(net 39 "/CSI Connector/GPIO4_1V8")
			(pintype "passive")
		)
		(pad "2" smd roundrect
			(at 0.48 0 180)
			(size 0.59 0.64)
			(layers "F.Cu" "F.Paste" "F.Mask")
			(roundrect_rratio 0.25)
			(net 1 "GND")
			(pintype "passive")
		)
	)
	(footprint "antmicro-footprints:L_Coilcraft-1210POC"
		(layer "F.Cu")
		(at 158.242 94.742 180)
		(property "Reference" "L4"
			(at -3.238 -0.328 180)
			(layer "F.SilkS")
			(effects
				(font
					(size 0.7 0.7)
					(thickness 0.15)
				)
				(justify right bottom)
			)
		)
		(property "Value" "L_6u8_1A_Coilcraft-1210POC"
			(at 0 2.4 0)
			(layer "F.Fab")
			(effects
				(font
					(size 0.7 0.7)
					(thickness 0.15)
				)
				(justify right bottom)
			)
		)
		(property "Footprint" "antmicro-footprints:L_Coilcraft-1210POC"
			(at 0 0 180)
			(layer "F.Fab")
			(hide yes)
			(effects
				(font
					(size 1.27 1.27)
					(thickness 0.15)
				)
			)
		)
		(property "Datasheet" "https://www.coilcraft.com/getmedia/5e8de018-68c5-4442-84ce-d5212c44660c/1210poc.pdf"
			(at 0 0 180)
			(layer "F.Fab")
			(hide yes)
			(effects
				(font
					(size 1.27 1.27)
					(thickness 0.15)
				)
			)
		)
		(property "Author" "Antmicro"
			(at 316.484 189.484 0)
			(layer "F.Fab")
			(hide yes)
			(effects
				(font
					(size 1 1)
					(thickness 0.15)
				)
			)
		)
		(property "IMax" "1.36 A"
			(at 316.484 189.484 0)
			(layer "F.Fab")
			(hide yes)
			(effects
				(font
					(size 1 1)
					(thickness 0.15)
				)
			)
		)
		(property "ISat" "1 A"
			(at 316.484 189.484 0)
			(layer "F.Fab")
			(hide yes)
			(effects
				(font
					(size 1 1)
					(thickness 0.15)
				)
			)
		)
		(property "License" "Apache-2.0"
			(at 316.484 189.484 0)
			(layer "F.Fab")
			(hide yes)
			(effects
				(font
					(size 1 1)
					(thickness 0.15)
				)
			)
		)
		(property "MPN" "1210POC-682"
			(at 316.484 189.484 0)
			(layer "F.Fab")
			(hide yes)
			(effects
				(font
					(size 1 1)
					(thickness 0.15)
				)
			)
		)
		(property "Manufacturer" "Coilcraft"
			(at 316.484 189.484 0)
			(layer "F.Fab")
			(hide yes)
			(effects
				(font
					(size 1 1)
					(thickness 0.15)
				)
			)
		)
		(property "Size" "2.67x3.3"
			(at 316.484 189.484 0)
			(layer "F.Fab")
			(hide yes)
			(effects
				(font
					(size 1 1)
					(thickness 0.15)
				)
			)
		)
		(property "Val" "6u8/1A"
			(at 316.484 189.484 0)
			(layer "F.Fab")
			(hide yes)
			(effects
				(font
					(size 1 1)
					(thickness 0.15)
				)
			)
		)
		(sheetname "GMSL Connector")
		(sheetfile "GMSL.kicad_sch")
		(attr smd)
		(fp_line
			(start -0.7 1.4)
			(end 0.7 1.4)
			(stroke
				(width 0.15)
				(type solid)
			)
			(layer "F.SilkS")
		)
		(fp_line
			(start -0.7 -1.4)
			(end 0.7 -1.4)
			(stroke
				(width 0.15)
				(type solid)
			)
			(layer "F.SilkS")
		)
		(fp_rect
			(start -1.9 -1.585)
			(end 1.9 1.585)
			(stroke
				(width 0.05)
				(type solid)
			)
			(fill none)
			(layer "F.CrtYd")
		)
		(fp_line
			(start 1.65 1.335)
			(end 1.65 -1.335)
			(stroke
				(width 0.15)
				(type solid)
			)
			(layer "F.Fab")
		)
		(fp_line
			(start 1.65 1.335)
			(end -1.65 1.335)
			(stroke
				(width 0.15)
				(type solid)
			)
			(layer "F.Fab")
		)
		(fp_line
			(start 1.65 -1.335)
			(end -1.65 -1.335)
			(stroke
				(width 0.15)
				(type solid)
			)
			(layer "F.Fab")
		)
		(fp_line
			(start -1.65 1.335)
			(end -1.65 -1.335)
			(stroke
				(width 0.15)
				(type solid)
			)
			(layer "F.Fab")
		)
		(fp_text user "${REFERENCE}"
			(at -2.1 3.95 0)
			(layer "F.Fab")
			(hide yes)
			(effects
				(font
					(size 0.7 0.7)
					(thickness 0.15)
				)
				(justify right bottom)
			)
		)
		(fp_text user "License: Apache-2.0"
			(at -2.1 6.35 0)
			(layer "F.Fab")
			(hide yes)
			(effects
				(font
					(size 0.7 0.7)
					(thickness 0.15)
				)
				(justify right bottom)
			)
		)
		(fp_text user "Author: Antmicro"
			(at -2.1 5.15 0)
			(layer "F.Fab")
			(hide yes)
			(effects
				(font
					(size 0.7 0.7)
					(thickness 0.15)
				)
				(justify right bottom)
			)
		)
		(pad "1" smd rect
			(at -1.27 0 180)
			(size 0.65 2.65)
			(layers "F.Cu" "F.Paste" "F.Mask")
			(net 58 "Net-(L3-Pad2)")
			(pintype "passive")
		)
		(pad "2" smd rect
			(at 1.27 0 180)
			(size 0.65 2.65)
			(layers "F.Cu" "F.Paste" "F.Mask")
			(net 59 "Net-(L4-Pad2)")
			(pintype "passive")
		)
	)
)
